(kicad_pcb
	(version 20260206)
	(generator "pcbnew")
	(generator_version "10.0")
	(general
		(thickness 1.6)
		(legacy_teardrops no)
	)
	(paper "A4")
	(title_block
		(title "01162023_DA0F0TEBIF0_F0T_Expander_BD_F_brd_V02_OCP.brd")
		(comment 1 "Grand Teton / footprints 7059-7065 of 9728")
	)
	(layers
		(0 "F.Cu" signal "TOP")
		(4 "In1.Cu" signal "GND")
		(6 "In2.Cu" signal "VCC")
		(8 "In3.Cu" signal "VCC1")
		(10 "In4.Cu" signal "GND1")
		(12 "In5.Cu" signal "IN1")
		(14 "In6.Cu" signal "GND2")
		(16 "In7.Cu" signal "IN2")
		(18 "In8.Cu" signal "GND3")
		(20 "In9.Cu" signal "IN3")
		(22 "In10.Cu" signal "GND4")
		(24 "In11.Cu" signal "IN4")
		(26 "In12.Cu" signal "GND5")
		(28 "In13.Cu" signal "IN5")
		(30 "In14.Cu" signal "GND6")
		(32 "In15.Cu" signal "IN6")
		(34 "In16.Cu" signal "GND7")
		(2 "B.Cu" signal "BOTTOM")
		(9 "F.Adhes" user "F.Adhesive")
		(11 "B.Adhes" user "B.Adhesive")
		(13 "F.Paste" user "Package Geometry/Pastemask Top")
		(15 "B.Paste" user "Package Geometry/Pastemask Bottom")
		(5 "F.SilkS" user "Ref Des/Silkscreen Top")
		(7 "B.SilkS" user "Ref Des/Silkscreen Bottom")
		(1 "F.Mask" user "Board Geometry/Soldermask Top")
		(3 "B.Mask" user "Board Geometry/Soldermask Bottom")
		(17 "Dwgs.User" user "User.Drawings")
		(19 "Cmts.User" user "User.Comments")
		(21 "Eco1.User" user "User.Eco1")
		(23 "Eco2.User" user "User.Eco2")
		(25 "Edge.Cuts" user "Board Geometry/Outline")
		(27 "Margin" user)
		(31 "F.CrtYd" user "Package Geometry/Place Bound Top")
		(29 "B.CrtYd" user "Package Geometry/Place Bound Bottom")
		(35 "F.Fab" user "Ref Des/Assembly Top")
		(33 "B.Fab" user "Ref Des/Assembly Bottom")
	)
	(footprint ""
		(layer "F.Cu")
		(at 247.401334 -55.78475 -90)
		(property "Reference" "PD111"
			(at 4.07035 2.188464 90)
			(unlocked yes)
			(layer "F.SilkS")
			(effects
				(font
					(size 0.7874 0.5842)
					(thickness 0.1524)
				)
				(justify left)
			)
		)
		(property "Value" ""
			(at 0 0 270)
			(layer "F.Fab")
			(effects
				(font
					(size 1.27 1.27)
				)
			)
		)
		(duplicate_pad_numbers_are_jumpers no)
		(fp_line
			(start -3.400044 1.459992)
			(end -3.400044 -1.459992)
			(stroke
				(width 0.1524)
				(type default)
			)
			(layer "F.SilkS")
		)
		(fp_line
			(start 4.107942 1.459992)
			(end -3.400044 1.459992)
			(stroke
				(width 0.1524)
				(type default)
			)
			(layer "F.SilkS")
		)
		(fp_line
			(start -3.400044 -1.459992)
			(end 4.107942 -1.459992)
			(stroke
				(width 0.1524)
				(type default)
			)
			(layer "F.SilkS")
		)
		(fp_line
			(start 4.107942 -1.459992)
			(end 4.107942 1.459992)
			(stroke
				(width 0.1524)
				(type default)
			)
			(layer "F.SilkS")
		)
		(fp_poly
			(pts
				(xy 4.107942 -1.459992) (xy 4.107942 1.459992) (xy 3.308096 1.459992) (xy 3.308096 -1.459992)
			)
			(stroke
				(width 0)
				(type default)
			)
			(fill yes)
			(layer "F.SilkS")
		)
		(fp_line
			(start -2.29997 1.459992)
			(end -2.29997 -1.459992)
			(stroke
				(width 0.1)
				(type default)
			)
			(layer "F.Fab")
		)
		(fp_line
			(start 2.29997 1.459992)
			(end -2.29997 1.459992)
			(stroke
				(width 0.1)
				(type default)
			)
			(layer "F.Fab")
		)
		(fp_line
			(start -2.29997 -1.459992)
			(end 2.29997 -1.459992)
			(stroke
				(width 0.1)
				(type default)
			)
			(layer "F.Fab")
		)
		(fp_line
			(start 2.29997 -1.459992)
			(end 2.29997 1.459992)
			(stroke
				(width 0.1)
				(type default)
			)
			(layer "F.Fab")
		)
		(fp_text user "-"
			(at 5.4102 0.29845 90)
			(unlocked yes)
			(layer "F.SilkS")
			(effects
				(font
					(size 1.905 1.4224)
					(thickness 0.1524)
				)
				(justify left)
			)
		)
		(fp_text user "+"
			(at -4.7752 -0.12065 270)
			(unlocked yes)
			(layer "F.SilkS")
			(effects
				(font
					(size 1.905 1.4224)
					(thickness 0.1524)
				)
				(justify left)
			)
		)
		(fp_text user "-"
			(at 5.4102 0.29845 90)
			(unlocked yes)
			(layer "F.Fab")
			(effects
				(font
					(size 1.905 1.4224)
					(thickness 0.1524)
				)
				(justify left)
			)
		)
		(fp_text user "+"
			(at -4.7752 -0.12065 270)
			(unlocked yes)
			(layer "F.Fab")
			(effects
				(font
					(size 1.905 1.4224)
					(thickness 0.1524)
				)
				(justify left)
			)
		)
		(pad "A" smd rect
			(at -1.999996 0)
			(size 1.7018 2.5146)
			(layers "F.Cu" "F.Mask" "F.Paste")
			(net "GND")
		)
		(pad "C" smd rect
			(at 1.999996 0)
			(size 1.7018 2.5146)
			(layers "F.Cu" "F.Mask" "F.Paste")
			(net "P12V_SSD8_R")
		)
	)
	(footprint ""
		(layer "F.Cu")
		(at 6.652768 -156.288994 -90)
		(property "Reference" "PR6862"
			(at 0 0 270)
			(layer "F.SilkS")
			(hide yes)
			(effects
				(font
					(size 1.27 1.27)
				)
			)
		)
		(property "Value" ""
			(at 0 0 270)
			(layer "F.Fab")
			(effects
				(font
					(size 1.27 1.27)
				)
			)
		)
		(duplicate_pad_numbers_are_jumpers no)
		(fp_line
			(start -0.7874 0.4064)
			(end -0.7874 -0.4064)
			(stroke
				(width 0.1524)
				(type default)
			)
			(layer "F.SilkS")
		)
		(fp_line
			(start 0.7874 0.4064)
			(end -0.7874 0.4064)
			(stroke
				(width 0.1524)
				(type default)
			)
			(layer "F.SilkS")
		)
		(fp_line
			(start -0.7874 -0.4064)
			(end 0.7874 -0.4064)
			(stroke
				(width 0.1524)
				(type default)
			)
			(layer "F.SilkS")
		)
		(fp_line
			(start 0.7874 -0.4064)
			(end 0.7874 0.4064)
			(stroke
				(width 0.1524)
				(type default)
			)
			(layer "F.SilkS")
		)
		(fp_line
			(start -0.67945 0.3048)
			(end -0.67945 -0.305054)
			(stroke
				(width 0.1)
				(type default)
			)
			(layer "F.Fab")
		)
		(fp_line
			(start -0.12065 0.3048)
			(end -0.67945 0.3048)
			(stroke
				(width 0.1)
				(type default)
			)
			(layer "F.Fab")
		)
		(fp_line
			(start 0.120396 0.3048)
			(end 0.120396 0.2794)
			(stroke
				(width 0.1)
				(type default)
			)
			(layer "F.Fab")
		)
		(fp_line
			(start 0.67945 0.3048)
			(end 0.120396 0.3048)
			(stroke
				(width 0.1)
				(type default)
			)
			(layer "F.Fab")
		)
		(fp_line
			(start -0.12065 0.2794)
			(end -0.12065 0.3048)
			(stroke
				(width 0.1)
				(type default)
			)
			(layer "F.Fab")
		)
		(fp_line
			(start 0.120396 0.2794)
			(end -0.12065 0.2794)
			(stroke
				(width 0.1)
				(type default)
			)
			(layer "F.Fab")
		)
		(fp_line
			(start -0.12065 -0.2794)
			(end 0.12065 -0.2794)
			(stroke
				(width 0.1)
				(type default)
			)
			(layer "F.Fab")
		)
		(fp_line
			(start 0.12065 -0.2794)
			(end 0.12065 -0.3048)
			(stroke
				(width 0.1)
				(type default)
			)
			(layer "F.Fab")
		)
		(fp_line
			(start 0.12065 -0.3048)
			(end 0.67945 -0.3048)
			(stroke
				(width 0.1)
				(type default)
			)
			(layer "F.Fab")
		)
		(fp_line
			(start 0.67945 -0.3048)
			(end 0.67945 0.3048)
			(stroke
				(width 0.1)
				(type default)
			)
			(layer "F.Fab")
		)
		(fp_line
			(start -0.67945 -0.305054)
			(end -0.12065 -0.305054)
			(stroke
				(width 0.1)
				(type default)
			)
			(layer "F.Fab")
		)
		(fp_line
			(start -0.12065 -0.305054)
			(end -0.12065 -0.2794)
			(stroke
				(width 0.1)
				(type default)
			)
			(layer "F.Fab")
		)
		(pad "1" smd circle
			(at -0.40005 0 270)
			(size 0 0)
			(layers "F.Cu" "F.Mask" "F.Paste")
			(net "P12V_NIC0_CO_OV_FB")
		)
		(pad "2" smd circle
			(at 0.40005 0 270)
			(size 0 0)
			(layers "F.Cu" "F.Mask" "F.Paste")
			(net "P12V_NIC0_R")
		)
	)
	(footprint ""
		(layer "F.Cu")
		(at 378.852684 -86.5378)
		(property "Reference" "R1769"
			(at 0 0 0)
			(layer "F.SilkS")
			(hide yes)
			(effects
				(font
					(size 1.27 1.27)
				)
			)
		)
		(property "Value" ""
			(at 0 0 0)
			(layer "F.Fab")
			(effects
				(font
					(size 1.27 1.27)
				)
			)
		)
		(duplicate_pad_numbers_are_jumpers no)
		(fp_line
			(start -0.7874 -0.4064)
			(end 0.7874 -0.4064)
			(stroke
				(width 0.1524)
				(type default)
			)
			(layer "F.SilkS")
		)
		(fp_line
			(start -0.7874 0.4064)
			(end -0.7874 -0.4064)
			(stroke
				(width 0.1524)
				(type default)
			)
			(layer "F.SilkS")
		)
		(fp_line
			(start 0.7874 -0.4064)
			(end 0.7874 0.4064)
			(stroke
				(width 0.1524)
				(type default)
			)
			(layer "F.SilkS")
		)
		(fp_line
			(start 0.7874 0.4064)
			(end -0.7874 0.4064)
			(stroke
				(width 0.1524)
				(type default)
			)
			(layer "F.SilkS")
		)
		(fp_line
			(start -0.67945 -0.305054)
			(end -0.12065 -0.305054)
			(stroke
				(width 0.1)
				(type default)
			)
			(layer "F.Fab")
		)
		(fp_line
			(start -0.67945 0.3048)
			(end -0.67945 -0.305054)
			(stroke
				(width 0.1)
				(type default)
			)
			(layer "F.Fab")
		)
		(fp_line
			(start -0.12065 -0.305054)
			(end -0.12065 -0.2794)
			(stroke
				(width 0.1)
				(type default)
			)
			(layer "F.Fab")
		)
		(fp_line
			(start -0.12065 -0.2794)
			(end 0.12065 -0.2794)
			(stroke
				(width 0.1)
				(type default)
			)
			(layer "F.Fab")
		)
		(fp_line
			(start -0.12065 0.2794)
			(end -0.12065 0.3048)
			(stroke
				(width 0.1)
				(type default)
			)
			(layer "F.Fab")
		)
		(fp_line
			(start -0.12065 0.3048)
			(end -0.67945 0.3048)
			(stroke
				(width 0.1)
				(type default)
			)
			(layer "F.Fab")
		)
		(fp_line
			(start 0.120396 0.2794)
			(end -0.12065 0.2794)
			(stroke
				(width 0.1)
				(type default)
			)
			(layer "F.Fab")
		)
		(fp_line
			(start 0.120396 0.3048)
			(end 0.120396 0.2794)
			(stroke
				(width 0.1)
				(type default)
			)
			(layer "F.Fab")
		)
		(fp_line
			(start 0.12065 -0.3048)
			(end 0.67945 -0.3048)
			(stroke
				(width 0.1)
				(type default)
			)
			(layer "F.Fab")
		)
		(fp_line
			(start 0.12065 -0.2794)
			(end 0.12065 -0.3048)
			(stroke
				(width 0.1)
				(type default)
			)
			(layer "F.Fab")
		)
		(fp_line
			(start 0.67945 -0.3048)
			(end 0.67945 0.3048)
			(stroke
				(width 0.1)
				(type default)
			)
			(layer "F.Fab")
		)
		(fp_line
			(start 0.67945 0.3048)
			(end 0.120396 0.3048)
			(stroke
				(width 0.1)
				(type default)
			)
			(layer "F.Fab")
		)
		(pad "1" smd circle
			(at -0.40005 0)
			(size 0 0)
			(layers "F.Cu" "F.Mask" "F.Paste")
			(net "SMB_BIC_I2C6_MUX_PEX_ADC_R_SDA")
		)
		(pad "2" smd circle
			(at 0.40005 0)
			(size 0 0)
			(layers "F.Cu" "F.Mask" "F.Paste")
			(net "SMB_BIC_I2C6_MUX_PEX_ADC_SDA")
		)
	)
	(footprint ""
		(layer "F.Cu")
		(at 163.047426 -21.37156)
		(property "Reference" "C3909"
			(at 0 0 0)
			(layer "F.SilkS")
			(hide yes)
			(effects
				(font
					(size 1.27 1.27)
				)
			)
		)
		(property "Value" ""
			(at 0 0 0)
			(layer "F.Fab")
			(effects
				(font
					(size 1.27 1.27)
				)
			)
		)
		(duplicate_pad_numbers_are_jumpers no)
		(fp_line
			(start -0.7874 -0.4064)
			(end 0.7874 -0.4064)
			(stroke
				(width 0.1524)
				(type default)
			)
			(layer "F.SilkS")
		)
		(fp_line
			(start -0.7874 0.4064)
			(end -0.7874 -0.4064)
			(stroke
				(width 0.1524)
				(type default)
			)
			(layer "F.SilkS")
		)
		(fp_line
			(start 0.7874 -0.4064)
			(end 0.7874 0.4064)
			(stroke
				(width 0.1524)
				(type default)
			)
			(layer "F.SilkS")
		)
		(fp_line
			(start 0.7874 0.4064)
			(end -0.7874 0.4064)
			(stroke
				(width 0.1524)
				(type default)
			)
			(layer "F.SilkS")
		)
		(fp_line
			(start -0.67945 -0.305054)
			(end -0.12065 -0.305054)
			(stroke
				(width 0.1)
				(type default)
			)
			(layer "F.Fab")
		)
		(fp_line
			(start -0.67945 0.3048)
			(end -0.67945 -0.305054)
			(stroke
				(width 0.1)
				(type default)
			)
			(layer "F.Fab")
		)
		(fp_line
			(start -0.12065 -0.305054)
			(end -0.12065 -0.2794)
			(stroke
				(width 0.1)
				(type default)
			)
			(layer "F.Fab")
		)
		(fp_line
			(start -0.12065 -0.2794)
			(end 0.12065 -0.2794)
			(stroke
				(width 0.1)
				(type default)
			)
			(layer "F.Fab")
		)
		(fp_line
			(start -0.12065 0.2794)
			(end -0.12065 0.3048)
			(stroke
				(width 0.1)
				(type default)
			)
			(layer "F.Fab")
		)
		(fp_line
			(start -0.12065 0.3048)
			(end -0.67945 0.3048)
			(stroke
				(width 0.1)
				(type default)
			)
			(layer "F.Fab")
		)
		(fp_line
			(start 0.120396 0.2794)
			(end -0.12065 0.2794)
			(stroke
				(width 0.1)
				(type default)
			)
			(layer "F.Fab")
		)
		(fp_line
			(start 0.120396 0.3048)
			(end 0.120396 0.2794)
			(stroke
				(width 0.1)
				(type default)
			)
			(layer "F.Fab")
		)
		(fp_line
			(start 0.12065 -0.3048)
			(end 0.67945 -0.3048)
			(stroke
				(width 0.1)
				(type default)
			)
			(layer "F.Fab")
		)
		(fp_line
			(start 0.12065 -0.2794)
			(end 0.12065 -0.3048)
			(stroke
				(width 0.1)
				(type default)
			)
			(layer "F.Fab")
		)
		(fp_line
			(start 0.67945 -0.3048)
			(end 0.67945 0.3048)
			(stroke
				(width 0.1)
				(type default)
			)
			(layer "F.Fab")
		)
		(fp_line
			(start 0.67945 0.3048)
			(end 0.120396 0.3048)
			(stroke
				(width 0.1)
				(type default)
			)
			(layer "F.Fab")
		)
		(pad "1" smd circle
			(at -0.40005 0)
			(size 0 0)
			(layers "F.Cu" "F.Mask" "F.Paste")
			(net "P12V_SSD5")
		)
		(pad "2" smd circle
			(at 0.40005 0)
			(size 0 0)
			(layers "F.Cu" "F.Mask" "F.Paste")
			(net "GND")
		)
	)
	(footprint ""
		(layer "F.Cu")
		(at 69.947028 -55.63489 90)
		(property "Reference" "PC650"
			(at 0 0 90)
			(layer "F.SilkS")
			(hide yes)
			(effects
				(font
					(size 1.27 1.27)
				)
			)
		)
		(property "Value" ""
			(at 0 0 90)
			(layer "F.Fab")
			(effects
				(font
					(size 1.27 1.27)
				)
			)
		)
		(duplicate_pad_numbers_are_jumpers no)
		(fp_line
			(start 1.524 -0.762)
			(end 1.524 0.762)
			(stroke
				(width 0.1524)
				(type default)
			)
			(layer "F.SilkS")
		)
		(fp_line
			(start -1.524 -0.762)
			(end 1.524 -0.762)
			(stroke
				(width 0.1524)
				(type default)
			)
			(layer "F.SilkS")
		)
		(fp_line
			(start 1.524 0.762)
			(end -1.524 0.762)
			(stroke
				(width 0.1524)
				(type default)
			)
			(layer "F.SilkS")
		)
		(fp_line
			(start -1.524 0.762)
			(end -1.524 -0.762)
			(stroke
				(width 0.1524)
				(type default)
			)
			(layer "F.SilkS")
		)
		(fp_line
			(start 1.1049 -0.724916)
			(end -1.1049 -0.724916)
			(stroke
				(width 0.1)
				(type default)
			)
			(layer "F.Fab")
		)
		(fp_line
			(start -1.1049 -0.724916)
			(end -1.1049 0.724916)
			(stroke
				(width 0.1)
				(type default)
			)
			(layer "F.Fab")
		)
		(fp_line
			(start 1.1049 0.724916)
			(end 1.1049 -0.724916)
			(stroke
				(width 0.1)
				(type default)
			)
			(layer "F.Fab")
		)
		(fp_line
			(start -1.1049 0.724916)
			(end 1.1049 0.724916)
			(stroke
				(width 0.1)
				(type default)
			)
			(layer "F.Fab")
		)
		(pad "1" smd rect
			(at -0.889 0 270)
			(size 1.016 1.27)
			(layers "F.Cu" "F.Mask" "F.Paste")
			(net "P12V_SSD2_R")
		)
		(pad "2" smd rect
			(at 0.889 0 270)
			(size 1.016 1.27)
			(layers "F.Cu" "F.Mask" "F.Paste")
			(net "GND")
		)
	)
	(footprint ""
		(layer "F.Cu")
		(at 151.469598 -260.088634 -90)
		(property "Reference" "R4571"
			(at 0 0 270)
			(layer "F.SilkS")
			(hide yes)
			(effects
				(font
					(size 1.27 1.27)
				)
			)
		)
		(property "Value" ""
			(at 0 0 270)
			(layer "F.Fab")
			(effects
				(font
					(size 1.27 1.27)
				)
			)
		)
		(duplicate_pad_numbers_are_jumpers no)
		(fp_line
			(start -0.7874 0.4064)
			(end -0.7874 -0.4064)
			(stroke
				(width 0.1524)
				(type default)
			)
			(layer "F.SilkS")
		)
		(fp_line
			(start 0.7874 0.4064)
			(end -0.7874 0.4064)
			(stroke
				(width 0.1524)
				(type default)
			)
			(layer "F.SilkS")
		)
		(fp_line
			(start -0.7874 -0.4064)
			(end 0.7874 -0.4064)
			(stroke
				(width 0.1524)
				(type default)
			)
			(layer "F.SilkS")
		)
		(fp_line
			(start 0.7874 -0.4064)
			(end 0.7874 0.4064)
			(stroke
				(width 0.1524)
				(type default)
			)
			(layer "F.SilkS")
		)
		(fp_line
			(start -0.67945 0.3048)
			(end -0.67945 -0.305054)
			(stroke
				(width 0.1)
				(type default)
			)
			(layer "F.Fab")
		)
		(fp_line
			(start -0.12065 0.3048)
			(end -0.67945 0.3048)
			(stroke
				(width 0.1)
				(type default)
			)
			(layer "F.Fab")
		)
		(fp_line
			(start 0.120396 0.3048)
			(end 0.120396 0.2794)
			(stroke
				(width 0.1)
				(type default)
			)
			(layer "F.Fab")
		)
		(fp_line
			(start 0.67945 0.3048)
			(end 0.120396 0.3048)
			(stroke
				(width 0.1)
				(type default)
			)
			(layer "F.Fab")
		)
		(fp_line
			(start -0.12065 0.2794)
			(end -0.12065 0.3048)
			(stroke
				(width 0.1)
				(type default)
			)
			(layer "F.Fab")
		)
		(fp_line
			(start 0.120396 0.2794)
			(end -0.12065 0.2794)
			(stroke
				(width 0.1)
				(type default)
			)
			(layer "F.Fab")
		)
		(fp_line
			(start -0.12065 -0.2794)
			(end 0.12065 -0.2794)
			(stroke
				(width 0.1)
				(type default)
			)
			(layer "F.Fab")
		)
		(fp_line
			(start 0.12065 -0.2794)
			(end 0.12065 -0.3048)
			(stroke
				(width 0.1)
				(type default)
			)
			(layer "F.Fab")
		)
		(fp_line
			(start 0.12065 -0.3048)
			(end 0.67945 -0.3048)
			(stroke
				(width 0.1)
				(type default)
			)
			(layer "F.Fab")
		)
		(fp_line
			(start 0.67945 -0.3048)
			(end 0.67945 0.3048)
			(stroke
				(width 0.1)
				(type default)
			)
			(layer "F.Fab")
		)
		(fp_line
			(start -0.67945 -0.305054)
			(end -0.12065 -0.305054)
			(stroke
				(width 0.1)
				(type default)
			)
			(layer "F.Fab")
		)
		(fp_line
			(start -0.12065 -0.305054)
			(end -0.12065 -0.2794)
			(stroke
				(width 0.1)
				(type default)
			)
			(layer "F.Fab")
		)
		(pad "1" smd circle
			(at -0.40005 0 270)
			(size 0 0)
			(layers "F.Cu" "F.Mask" "F.Paste")
			(net "PCEPLL3_VDDA18_PEX1")
		)
		(pad "2" smd circle
			(at 0.40005 0 270)
			(size 0 0)
			(layers "F.Cu" "F.Mask" "F.Paste")
			(net "PCEPLL3_VDDA18_PEX1_R")
		)
	)
	(footprint ""
		(layer "F.Cu")
		(at 185.89244 -32.739584 180)
		(property "Reference" "C294"
			(at 0 0 180)
			(layer "F.SilkS")
			(hide yes)
			(effects
				(font
					(size 1.27 1.27)
				)
			)
		)
		(property "Value" ""
			(at 0 0 180)
			(layer "F.Fab")
			(effects
				(font
					(size 1.27 1.27)
				)
			)
		)
		(duplicate_pad_numbers_are_jumpers no)
		(fp_line
			(start 0.299974 0.150114)
			(end -0.299974 0.150114)
			(stroke
				(width 0.1)
				(type default)
			)
			(layer "F.Fab")
		)
		(fp_line
			(start 0.299974 -0.150114)
			(end 0.299974 0.150114)
			(stroke
				(width 0.1)
				(type default)
			)
			(layer "F.Fab")
		)
		(fp_line
			(start -0.299974 0.150114)
			(end -0.299974 -0.150114)
			(stroke
				(width 0.1)
				(type default)
			)
			(layer "F.Fab")
		)
		(fp_line
			(start -0.299974 -0.150114)
			(end 0.299974 -0.150114)
			(stroke
				(width 0.1)
				(type default)
			)
			(layer "F.Fab")
		)
		(pad "1" smd rect
			(at -0.2667 0 180)
			(size 0.3048 0.381)
			(layers "F.Cu" "F.Mask" "F.Paste")
			(net "P5E_PEX1_STN2_TX_DP<38>")
		)
		(pad "2" smd rect
			(at 0.2667 0 180)
			(size 0.3048 0.381)
			(layers "F.Cu" "F.Mask" "F.Paste")
			(net "P5E_PEX1_STN2_TX_C_DP<38>")
		)
	)
)
